FILE_TYPE = CONNECTIVITY;
{Allegro Design Entry HDL 17.4-2019 S026 (4007227) 1/17/2022}
"PAGE_NUMBER" = 338;
0"NC";
1"GND\g";
2"GND\g";
3"GND\g";
4"P12V_AUX\g";
5"GND\g";
6"GND\g";
7"GND\g";
8"GND\g";
9"GND\g";
10"GND\g";
11"GND\g";
12"GND\g";
13"P12V_AUX\g";
14"GND\g";
15"GND\g";
16"GND\g";
17"OCP_SFF_PRSNT0_R_N"CDS_PHYS_NET_NAME"OCP_SFF_PRSNT0_R_N";
18"OCP_SFF_PRSNT1_R_N"CDS_PHYS_NET_NAME"OCP_SFF_PRSNT1_R_N";
19"P3V3_AUX\g";
20"GND\g";
21"P12V_OCP_SENSE_1";
22"P12V_OCP_GATE_1";
23"GND\g";
24"P12V_AUX\g";
25"P12V_OCP_VCC_1";
26"P12V_OCP_OV_1";
27"P3V3_OCP_EN_1_R";
28"GND\g";
29"P3V3_OCP_SENSE_1";
30"P3V3_AUX\g";
31"P12V_OCP_UV_1";
32"GND\g";
33"P3V3_AUX\g";
34"GND\g";
35"P3V3_AUX\g";
36"GND\g";
37"P3V3_AUX\g";
38"P3V3_AUX\g";
39"GND\g";
40"GND\g";
41"P3V3_OCP_SFF_R\g";
42"GND\g";
43"P3V3_AUX\g";
44"P3V3_OCP_REG_1";
45"P3V3_OCP_VCC_1";
46"P12V_OCP_SFF_EN_R";
47"P12V_OCP_UV_1_R";
48"P12V_OCP_1_EN_G";
49"P3V3_OCP_GATE_PU202_1";
50"P3V3_OCP_OV_1";
51"P3V3_OCP_CB_1";
52"HP_LVC3_OCP_SFF_PRSNT2_PLD_N"CDS_PHYS_NET_NAME"HP_LVC3_OCP_V3_1_PRSNT2_N";
53"HP_LVC3_OCP_V3_1_PRSNT2_N_R"CDS_PHYS_NET_NAME"HP_LVC3_OCP_V3_1_PRSNT2_N_R";
54"HP_LVC3_OCP_SFF_PRSNT2_N";
55"OCP_SFF_PRSNT2_R_N"CDS_PHYS_NET_NAME"OCP_SFF_PRSNT2_R_N";
56"OCP_SFF_PRSNT3_R_N"CDS_PHYS_NET_NAME"OCP_SFF_PRSNT3_R_N";
57"P3V3_OCP_UV_1";
58"P12V_OCP_REG_1";
59"P3V3_AUX\g";
60"P3V3_OCP_1_EN_G";
61"P12V_OCP_SFF_BUF_EN_R";
62"P12V_OCP_SFF_BUF_EN_R";
63"P3V3_OCP_PWRGD_1";
64"P3V3_OCP_FAULT_1";
65"P12V_OCP_EN_1_R";
66"P12V_OCP_PWRGD_1";
67"P12V_OCP_SFF_ISENSE_MAM_MAM";
68"P12V_OCP_SFF_ISENSE_MAM_TIC";
69"GND\g";
70"P3V3_OCP_UV_1_R1";
71"P3V3_OCP_SFF_EN_R";
72"HP_LVC3_OCP_V3_1_P12V_PWRGD";
73"HP_LVC3_OCP_V3_1_P12V_PWRGD";
74"P12V_OCP_CB_1";
75"P12V_OCP_FAULT_1";
76"P12V_OCP_SFF\g";
77"OCP_V3_1_P3V3_PWRGD";
%"UNIVERSAL_GND"
"1","(5950,8175)","0","pure_quanta_power","I1";
;
CDS_LIB"pure_quanta_power"
HDL_POWER"GND";
"A"1;
%"UNIVERSAL_POWER"
"1","(3900,9150)","0","pure_quanta_power","I10";
;
HDL_POWER"P3V3_AUX"
CDS_LIB"pure_quanta_power";
"A"19;
%"Q_CAP"
"1","(9275,12875)","1","pure_quanta","I100";
;
LOCATION"PC2089"
$SEC"1"
CDS_SEC"1"
VOLTAGE"50V"
ROOM"NIC_P3V3_BOM1"
VALUE"6800PF"
PACK_TYPE"C0402"
CDS_LIB"pure_quanta"
MATERIAL"X7R"
TOLERANCE"10%"
PART_NUMBER"CH2686K1B01";
"B"
$PN"2"16;
"A"
$PN"1"49;
%"Q_RES"
"2","(9675,13050)","0","pure_quanta","I101";
;
LOCATION"R3796"
$SEC"1"
CDS_SEC"1"
MATERIAL"CHIP"
TOLERANCE"1%"
ROOM"NIC_P3V3_BOM1"
VALUE"100K"
WATTAGE"1/16W"
PACK_TYPE"0402LF"
CDS_LIB"pure_quanta"
PART_NUMBER"CS41002FB09";
"A"
$PN"1"43;
"B"
$PN"2"64;
%"VCCAUX15"
"1","(9875,13325)","0","pure_quanta_power","I102";
;
HDL_POWER"P3V3_AUX"
CDS_LIB"pure_quanta_power";
"A"43;
%"Q_CAP"
"1","(9550,13650)","0","pure_quanta","I104";
;
LOCATION"PC2091"
$SEC"1"
CDS_SEC"1"
PACK_TYPE"0402"
VOLTAGE"25V"
MATERIAL"X7R"
VALUE"0.1UF"
TOLERANCE"10%"
CDS_LIB"pure_quanta"
PART_NUMBER"CH4104K1B00";
"B"
$PN"2"42;
"A"
$PN"1"41;
%"GND"
"1","(10125,13350)","0","pure_quanta_power","I105";
;
SIZE"1B"
CDS_LIB"pure_quanta_power"
HDL_POWER"GND";
"A<SIZE-1..0>\NAC"42;
%"Q_CAP"
"1","(10125,13650)","0","pure_quanta","I106";
;
LOCATION"PC2081"
$SEC"1"
CDS_SEC"1"
PACK_TYPE"C0805"
MATERIAL"X6S"
VALUE"10UF"
VOLTAGE"16V"
TOLERANCE"10%"
CDS_LIB"pure_quanta"
PART_NUMBER"CH6103KEA01";
"B"
$PN"2"42;
"A"
$PN"1"41;
%"UNIVERSAL_POWER"
"1","(10125,13950)","2","pure_quanta_power","I107";
;
HDL_POWER"P3V3_OCP_SFF_R"
CDS_LIB"pure_quanta_power";
"A"41;
%"GND"
"1","(5900,13225)","0","pure_quanta_power","I109";
;
SIZE"1B"
CDS_LIB"pure_quanta_power"
HDL_POWER"GND";
"A<SIZE-1..0>\NAC"2;
%"MOSFET_NCH_DUAL"
"1","(3575,10275)","0","pure_quanta","I11";
;
LOCATION"Q123"
$SEC"1"
CDS_SEC"1"
PART_TYPE"SMLF"
MATERIAL"IC"
VALUE"PJT138K"
ROOM"NIC_P12V_MAM_TIC_BOM1"
NEEDS_NO_SIZE"TRUE"
CDS_LMAN_SYM_OUTLINE"-150,150,150,-150"
CDS_LIB"pure_quanta"
PART_NUMBER"BAM138K0003";
"D1"
$PN"6"48;
"G1"
$PN"2"65;
"S1"
$PN"1"3;
%"Q_CAP"
"1","(6575,13075)","0","pure_quanta","I110";
;
LOCATION"PC2086"
$SEC"1"
CDS_SEC"1"
ROOM"NIC_P3V3_BOM1"
VALUE"1UF"
MATERIAL"X6S"
VOLTAGE"25V"
PACK_TYPE"C0402"
CDS_LIB"pure_quanta"
TOLERANCE"10%"
PART_NUMBER"CH5104KEB02";
"B"
$PN"2"14;
"A"
$PN"1"45;
%"Q_RES"
"2","(7100,12275)","0","pure_quanta","I111";
;
LOCATION"PR3780"
$SEC"1"
CDS_SEC"1"
MATERIAL"CHIP"
PACK_TYPE"0402LF"
WATTAGE"1/16W"
TOLERANCE"1%"
VALUE"5.36K"
ROOM"NIC_P3V3_BOM1"
CDS_LIB"pure_quanta"
PART_NUMBER"CS25362FB02";
"A"
$PN"1"51;
"B"
$PN"2"69;
%"MOSFET_NCH_DUAL"
"2","(4925,12250)","0","pure_quanta","I112";
;
LOCATION"Q124"
$SEC"2"
CDS_SEC"2"
PART_TYPE"SMLF"
ROOM"NIC_P3V3_BOM1"
MATERIAL"IC"
VALUE"PJT138K"
CDS_LIB"pure_quanta"
CDS_LMAN_SYM_OUTLINE"-150,150,150,-150"
NEEDS_NO_SIZE"TRUE"
PART_NUMBER"BAM138K0003";
"S2"
$PN"4"10;
"G2"
$PN"5"60;
"D2"
$PN"3"70;
%"MAX15090BEWIT"
"1","(7850,12775)","0","pure_quanta","I113";
;
LOCATION"PU202"
$SEC"1"
CDS_SEC"1"
ROOM"NIC_P3V3_BOM1"
PART_TYPE"SMLF"
VALUE"MAX15090BEWI+T"
MATERIAL"IC"
CDS_LMAN_SYM_OUTLINE"-250,550,250,-550"
PIN_NAMES_ROTATE"True"
CDS_LIB"pure_quanta"
PART_NUMBER"AL015080B00";
"PG"
$PN"D7"63;
"FAULT# \B"
$PN"C7"64;
"GND_C2"
$PN"C2"28;
"GND_C1"
$PN"C1"28;
"GND_B2"
$PN"B2"28;
"CDLY"
$PN"A7"28;
"GATE"
$PN"A6"49;
"OUT_D6"
$PN"D6"41;
"OUT_D4"
$PN"D4"41;
"OUT_C6"
$PN"C6"41;
"OUT_C4"
$PN"C4"41;
"OUT_B6"
$PN"B6"41;
"OUT_B4"
$PN"B4"41;
"OUT_A4"
$PN"A4"41;
"ISENSE"
$PN"A1"29;
"OV"
$PN"D3"50;
"UV"
$PN"D2"57;
"REG"
$PN"D1"44;
"EN# \B"
$PN"B7"69;
"CB"
$PN"B1"51;
"IN_D5"
$PN"D5"33;
"IN_C5"
$PN"C5"33;
"IN_C3"
$PN"C3"33;
"IN_B5"
$PN"B5"33;
"IN_B3"
$PN"B3"33;
"IN_A5"
$PN"A5"33;
"IN_A3"
$PN"A3"33;
"VCC"
$PN"A2"45;
%"Q_RES"
"2","(6250,12250)","0","pure_quanta","I114";
;
LOCATION"PR3791"
$SEC"1"
CDS_SEC"1"
ROOM"NIC_P3V3_BOM1"
TOLERANCE"1%"
WATTAGE"1/16W"
MATERIAL"CHIP"
PACK_TYPE"0402LF"
VALUE"15K"
CDS_LIB"pure_quanta"
PART_NUMBER"CS31502FB05";
"A"
$PN"1"50;
"B"
$PN"2"12;
%"DIODE_TVS"
"1","(5300,11450)","1","pure_quanta","I115";
;
LOCATION"PD101"
$SEC"1"
CDS_SEC"1"
VALUE"SMF14A"
MATERIAL"IC"
CDS_LIB"pure_quanta"
CDS_LMAN_SYM_OUTLINE"-100,50,100,-50"
PART_TYPE"SMLF"
PIN_NAMES_ROTATE"True"
PART_NUMBER"BCSMF14AZ01";
"C"
$PN"C"
Pin_Length"Short"24;
"A"
$PN"A"20;
%"Q_RES"
"1","(6850,8675)","0","pure_quanta","I116";
;
LOCATION"R576"
$SEC"1"
CDS_SEC"1"
VALUE"0"
TOLERANCE"5%"
WATTAGE"1/16W"
PACK_TYPE"0402LF"
MATERIAL"CHIP"
CDS_LIB"pure_quanta"
PART_NUMBER"CS00002JB13";
"B"
$PN"2"54;
"A"
$PN"1"53;
%"Q_RES"
"2","(8200,9325)","2","pure_quanta","I118";
;
LOCATION"R577"
$SEC"1"
CDS_SEC"1"
PACK_TYPE"0402LF"
VALUE"10K"
MATERIAL"CHIP"
WATTAGE"1/16W"
TOLERANCE"1%"
CDS_LIB"pure_quanta"
PART_NUMBER"CS31002FB08";
"A"
$PN"1"35;
"B"
$PN"2"54;
%"GND"
"1","(3625,9925)","0","pure_quanta_power","I12";
;
CDS_LIB"pure_quanta_power"
SIZE"1B"
HDL_POWER"GND";
"A<SIZE-1..0>\NAC"3;
%"Q_RES"
"1","(2600,10225)","0","pure_quanta","I123";
;
LOCATION"R4061"
$SEC"1"
CDS_SEC"1"
TOLERANCE"5%"
VALUE"0"
ROOM"NIC_P12V_MAM_TIC_BOM1"
MATERIAL"EMPTY"
CDS_LIB"pure_quanta"
PACK_TYPE"0402LF"
WATTAGE"1/16W"
PART_NUMBER"CS00002JB13";
"B"
$PN"2"65;
"A"
$PN"1"46;
%"Q_RES"
"1","(2900,10650)","0","pure_quanta","I125";
;
LOCATION"R561"
$SEC"1"
CDS_SEC"1"
VALUE"0"
MATERIAL"CHIP"
ROOM"NIC_P12V_MAM_TIC_BOM1"
TOLERANCE"5%"
PACK_TYPE"0402LF"
WATTAGE"1/16W"
CDS_LIB"pure_quanta"
PART_NUMBER"CS00002JB13";
"B"
$PN"2"65;
"A"
$PN"1"61;
%"Q_RES"
"1","(3275,11825)","0","pure_quanta","I126";
;
LOCATION"R5487"
$SEC"1"
CDS_SEC"1"
ROOM"NIC_P3V3_BOM1"
VALUE"0"
TOLERANCE"5%"
PACK_TYPE"0402LF"
MATERIAL"EMPTY"
WATTAGE"1/16W"
CDS_LIB"pure_quanta"
PART_NUMBER"CS00002JB13";
"B"
$PN"2"27;
"A"
$PN"1"71;
%"Q_RES"
"2","(3650,11500)","2","pure_quanta","I127";
;
LOCATION"R4069"
$SEC"1"
CDS_SEC"1"
VALUE"4.7K"
MATERIAL"EMPTY"
ROOM"NIC_P3V3_BOM1"
PACK_TYPE"0402LF"
WATTAGE"1/16W"
TOLERANCE"5%"
CDS_LIB"pure_quanta"
PART_NUMBER"CS24702JB10";
"A"
$PN"1"27;
"B"
$PN"2"5;
%"Q_RES"
"2","(3025,9900)","2","pure_quanta","I130";
;
LOCATION"R6045"
$SEC"1"
CDS_SEC"1"
WATTAGE"1/16W"
PACK_TYPE"0402LF"
TOLERANCE"5%"
VALUE"4.7K"
MATERIAL"EMPTY"
ROOM"NIC_P12V_MAM_TIC_BOM1"
CDS_LIB"pure_quanta"
PART_NUMBER"CS24702JB10";
"A"
$PN"1"65;
"B"
$PN"2"11;
%"Q_RES"
"2","(10225,13050)","0","pure_quanta","I131";
;
LOCATION"R3783"
$SEC"1"
CDS_SEC"1"
PACK_TYPE"0402LF"
ROOM"NIC_P3V3_BOM1"
MATERIAL"EMPTY"
WATTAGE"1/16W"
TOLERANCE"1%"
VALUE"100K"
CDS_LIB"pure_quanta"
PART_NUMBER"CS41002FB09";
"A"
$PN"1"43;
"B"
$PN"2"77;
%"Q_RES"
"1","(9325,12775)","0","pure_quanta","I132";
;
LOCATION"R3794"
$SEC"1"
CDS_SEC"1"
MATERIAL"EMPTY"
WATTAGE"1/16W"
ROOM"NIC_P3V3_BOM1"
VALUE"0"
TOLERANCE"5%"
PACK_TYPE"0402LF"
CDS_LIB"pure_quanta"
PART_NUMBER"CS00002JB13";
"B"
$PN"2"77;
"A"
$PN"1"63;
%"Q_RES"
"1","(3325,12225)","0","pure_quanta","I133";
;
LOCATION"R1136"
$SEC"1"
CDS_SEC"1"
TOLERANCE"5%"
VALUE"0"
PACK_TYPE"0402LF"
ROOM"NIC_P3V3_BOM1"
MATERIAL"EMPTY"
CDS_LIB"pure_quanta"
WATTAGE"1/16W"
PART_NUMBER"CS00002JB13";
"B"
$PN"2"27;
"A"
$PN"1"73;
%"Q_RES"
"1","(3275,12650)","0","pure_quanta","I135";
;
LOCATION"R1486"
$SEC"1"
CDS_SEC"1"
ROOM"NIC_P3V3_BOM1"
PACK_TYPE"0402LF"
MATERIAL"CHIP"
WATTAGE"1/16W"
TOLERANCE"5%"
VALUE"0"
CDS_LIB"pure_quanta"
PART_NUMBER"CS00002JB13";
"B"
$PN"2"27;
"A"
$PN"1"62;
%"Q_RES"
"2","(3950,9750)","0","pure_quanta","I15";
;
LOCATION"R1905"
$SEC"1"
CDS_SEC"1"
WATTAGE"1/16W"
TOLERANCE"1%"
PACK_TYPE"0402LF"
MATERIAL"CHIP"
VALUE"1K"
CDS_LIB"pure_quanta"
PART_NUMBER"CS21002FB06";
"A"
$PN"1"59;
"B"
$PN"2"17;
%"UNIVERSAL_POWER"
"1","(4150,10050)","0","pure_quanta_power","I16";
;
HDL_POWER"P3V3_AUX"
CDS_LIB"pure_quanta_power";
"A"59;
%"Q_RES"
"2","(3475,10800)","0","pure_quanta","I17";
;
LOCATION"R4068"
$SEC"1"
CDS_SEC"1"
PACK_TYPE"0402LF"
VALUE"10K"
WATTAGE"1/16W"
TOLERANCE"1%"
MATERIAL"CHIP"
ROOM"NIC_P12V_MAM_TIC_BOM1"
CDS_LIB"pure_quanta"
PART_NUMBER"CS31002FB08";
"A"
$PN"1"4;
"B"
$PN"2"48;
%"UNIVERSAL_POWER"
"1","(3475,11125)","0","pure_quanta_power","I18";
;
HDL_POWER"P12V_AUX"
CDS_LIB"pure_quanta_power";
"A"4;
%"MOSFET_NCH_DUAL"
"2","(4425,10575)","0","pure_quanta","I19";
;
LOCATION"Q123"
$SEC"2"
CDS_SEC"2"
MATERIAL"IC"
ROOM"NIC_P12V_MAM_TIC_BOM1"
PART_TYPE"SMLF"
VALUE"PJT138K"
CDS_LIB"pure_quanta"
CDS_LMAN_SYM_OUTLINE"-150,150,150,-150"
NEEDS_NO_SIZE"TRUE"
PART_NUMBER"BAM138K0003";
"S2"
$PN"4"8;
"G2"
$PN"5"48;
"D2"
$PN"3"47;
%"GND"
"1","(3650,11250)","0","pure_quanta_power","I20";
;
CDS_LIB"pure_quanta_power"
SIZE"1B"
HDL_POWER"GND";
"A<SIZE-1..0>\NAC"5;
%"MOSFET_NCH_DUAL"
"1","(4175,11875)","0","pure_quanta","I23";
;
LOCATION"Q124"
$SEC"1"
CDS_SEC"1"
PART_TYPE"SMLF"
VALUE"PJT138K"
ROOM"NIC_P3V3_BOM1"
MATERIAL"IC"
CDS_LIB"pure_quanta"
CDS_LMAN_SYM_OUTLINE"-150,150,150,-150"
NEEDS_NO_SIZE"TRUE"
PART_NUMBER"BAM138K0003";
"D1"
$PN"6"60;
"G1"
$PN"2"27;
"S1"
$PN"1"9;
%"Q_RES"
"2","(4125,8850)","0","pure_quanta","I24";
;
LOCATION"R1908"
$SEC"1"
CDS_SEC"1"
TOLERANCE"1%"
PACK_TYPE"0402LF"
MATERIAL"CHIP"
WATTAGE"1/16W"
VALUE"1K"
CDS_LIB"pure_quanta"
PART_NUMBER"CS21002FB06";
"A"
$PN"1"19;
"B"
$PN"2"56;
%"UNIVERSAL_GND"
"1","(4875,8250)","0","pure_quanta_power","I25";
;
CDS_LIB"pure_quanta_power"
HDL_POWER"GND";
"A"40;
%"74LVC2G07DW7"
"1","(5275,8550)","0","pure_quanta","I26";
;
LOCATION"U8"
$SEC"1"
CDS_SEC"1"
VALUE"74LVC2G07DW-7"
MATERIAL"IC"
PART_TYPE"SMLF"
NEEDS_NO_SIZE"TRUE"
CDS_LMAN_SYM_OUTLINE"-175,100,175,-100"
CDS_LIB"pure_quanta"
PART_NUMBER"AL002G07003";
"VCC"
$PN"5"38;
"GND"
$PN"2"40;
"2Y"
$PN"4"53;
"1Y"
$PN"6"53;
"2A"
$PN"3"56;
"1A"
$PN"1"55;
%"UNIVERSAL_GND"
"1","(4875,9175)","0","pure_quanta_power","I27";
;
CDS_LIB"pure_quanta_power"
HDL_POWER"GND";
"A"39;
%"Q_RES"
"2","(4225,9750)","0","pure_quanta","I28";
;
LOCATION"R1907"
$SEC"1"
CDS_SEC"1"
MATERIAL"CHIP"
PACK_TYPE"0402LF"
TOLERANCE"1%"
VALUE"1K"
WATTAGE"1/16W"
CDS_LIB"pure_quanta"
PART_NUMBER"CS21002FB06";
"A"
$PN"1"59;
"B"
$PN"2"18;
%"74LVC2G07DW7"
"1","(5275,9450)","0","pure_quanta","I29";
;
LOCATION"U211"
$SEC"1"
CDS_SEC"1"
MATERIAL"IC"
VALUE"74LVC2G07DW-7"
PART_TYPE"SMLF"
NEEDS_NO_SIZE"TRUE"
CDS_LMAN_SYM_OUTLINE"-175,100,175,-100"
CDS_LIB"pure_quanta"
PART_NUMBER"AL002G07003";
"VCC"
$PN"5"37;
"GND"
$PN"2"39;
"2Y"
$PN"4"53;
"1Y"
$PN"6"53;
"2A"
$PN"3"18;
"1A"
$PN"1"17;
%"Q_CAP"
"1","(5950,8375)","0","pure_quanta","I30";
;
LOCATION"C593"
$SEC"1"
CDS_SEC"1"
PACK_TYPE"0402"
VALUE"0.1UF"
VOLTAGE"25V"
TOLERANCE"10%"
MATERIAL"X7R"
CDS_LIB"pure_quanta"
PART_NUMBER"CH4104K1B00";
"B"
$PN"2"1;
"A"
$PN"1"38;
%"UNIVERSAL_POWER"
"1","(5950,8650)","0","pure_quanta_power","I31";
;
HDL_POWER"P3V3_AUX"
CDS_LIB"pure_quanta_power";
"A"38;
%"UNIVERSAL_GND"
"1","(5950,9075)","0","pure_quanta_power","I32";
;
CDS_LIB"pure_quanta_power"
HDL_POWER"GND";
"A"6;
%"Q_CAP"
"1","(5950,9275)","0","pure_quanta","I33";
;
LOCATION"C592"
$SEC"1"
CDS_SEC"1"
PACK_TYPE"0402"
TOLERANCE"10%"
MATERIAL"X7R"
VALUE"0.1UF"
VOLTAGE"25V"
CDS_LIB"pure_quanta"
PART_NUMBER"CH4104K1B00";
"B"
$PN"2"6;
"A"
$PN"1"37;
%"UNIVERSAL_POWER"
"1","(5950,9550)","0","pure_quanta_power","I34";
;
HDL_POWER"P3V3_AUX"
CDS_LIB"pure_quanta_power";
"A"37;
%"GND"
"1","(6025,9950)","0","pure_quanta_power","I35";
;
CDS_LIB"pure_quanta_power"
SIZE"1B"
HDL_POWER"GND";
"A<SIZE-1..0>\NAC"7;
%"Q_RES"
"2","(6025,10200)","0","pure_quanta","I36";
;
LOCATION"PR3788"
$SEC"1"
CDS_SEC"1"
ROOM"NIC_P12V_MAM_TIC_BOM1"
MATERIAL"CHIP"
WATTAGE"1/16W"
VALUE"15K"
TOLERANCE"1%"
PACK_TYPE"0402LF"
CDS_LIB"pure_quanta"
PART_NUMBER"CS31502FB05";
"A"
$PN"1"26;
"B"
$PN"2"7;
%"GND"
"1","(4475,10275)","0","pure_quanta_power","I37";
;
CDS_LIB"pure_quanta_power"
SIZE"1B"
HDL_POWER"GND";
"A<SIZE-1..0>\NAC"8;
%"GND"
"1","(4225,11525)","0","pure_quanta_power","I38";
;
SIZE"1B"
CDS_LIB"pure_quanta_power"
HDL_POWER"GND";
"A<SIZE-1..0>\NAC"9;
%"GND"
"1","(4975,11900)","0","pure_quanta_power","I39";
;
SIZE"1B"
CDS_LIB"pure_quanta_power"
HDL_POWER"GND";
"A<SIZE-1..0>\NAC"10;
%"Q_RES"
"1","(5500,10825)","0","pure_quanta","I40";
;
LOCATION"R3784"
$SEC"1"
CDS_SEC"1"
WATTAGE"1/16W"
VALUE"0"
TOLERANCE"5%"
MATERIAL"CHIP"
PACK_TYPE"0402LF"
ROOM"NIC_P12V_MAM_TIC_BOM1"
CDS_LIB"pure_quanta"
PART_NUMBER"CS00002JB13";
"B"
$PN"2"31;
"A"
$PN"1"47;
%"GND"
"1","(5450,11075)","0","pure_quanta_power","I41";
;
SIZE"1B"
CDS_LIB"pure_quanta_power"
HDL_POWER"GND";
"A<SIZE-1..0>\NAC"20;
%"Q_RES"
"2","(6025,10475)","0","pure_quanta","I42";
;
LOCATION"PR3787"
$SEC"1"
CDS_SEC"1"
ROOM"NIC_P12V_MAM_TIC_BOM1"
MATERIAL"CHIP"
WATTAGE"1/16W"
VALUE"6.8K"
TOLERANCE"1%"
PACK_TYPE"0402LF"
CDS_LIB"pure_quanta"
PART_NUMBER"CS26802FB02";
"A"
$PN"1"31;
"B"
$PN"2"26;
%"Q_RES"
"2","(6025,11150)","0","pure_quanta","I43";
;
LOCATION"PR3786"
$SEC"1"
CDS_SEC"1"
VALUE"160K"
TOLERANCE"1%"
WATTAGE"1/16W"
MATERIAL"CHIP"
ROOM"NIC_P12V_MAM_TIC_BOM1"
PACK_TYPE"0402LF"
CDS_LIB"pure_quanta"
PART_NUMBER"CS41602FB05";
"A"
$PN"1"24;
"B"
$PN"2"31;
%"UNIVERSAL_POWER"
"1","(5450,11800)","0","pure_quanta_power","I44";
;
HDL_POWER"P12V_AUX"
CDS_LIB"pure_quanta_power";
"A"24;
%"Q_CAP"
"1","(5675,11450)","0","pure_quanta","I45";
;
LOCATION"PC2079"
$SEC"1"
CDS_SEC"1"
VALUE"1UF"
VOLTAGE"25V"
MATERIAL"X6S"
PACK_TYPE"C0402"
CDS_LIB"pure_quanta"
TOLERANCE"10%"
PART_NUMBER"CH5104KEB02";
"B"
$PN"2"20;
"A"
$PN"1"24;
%"Q_RES"
"1","(6850,8900)","0","pure_quanta","I46";
;
LOCATION"R1148"
$SEC"1"
CDS_SEC"1"
TOLERANCE"5%"
WATTAGE"1/16W"
MATERIAL"CHIP"
VALUE"0"
PACK_TYPE"0402LF"
CDS_LIB"pure_quanta"
PART_NUMBER"CS00002JB13";
"B"
$PN"2"52;
"A"
$PN"1"53;
%"Q_RES"
"2","(6875,10225)","0","pure_quanta","I48";
;
LOCATION"PR5484"
$SEC"1"
CDS_SEC"1"
ROOM"NIC_P12V_MAM_TIC_BOM1"
TOLERANCE"1%"
MATERIAL"CHIP"
PACK_TYPE"0402LF"
VALUE"30.1K"
WATTAGE"1/16W"
CDS_LIB"pure_quanta"
PART_NUMBER"CS33012FB03";
"A"
$PN"1"74;
"B"
$PN"2"36;
%"GND"
"1","(6875,9925)","0","pure_quanta_power","I49";
;
CDS_LIB"pure_quanta_power"
SIZE"1B"
HDL_POWER"GND";
"A<SIZE-1..0>\NAC"36;
%"GND"
"1","(3025,9650)","0","pure_quanta_power","I5";
;
CDS_LIB"pure_quanta_power"
SIZE"1B"
HDL_POWER"GND";
"A<SIZE-1..0>\NAC"11;
%"MAX15090BEWIT"
"1","(7625,10725)","0","pure_quanta","I50";
;
LOCATION"PU203"
$SEC"1"
CDS_SEC"1"
MATERIAL"IC"
VALUE"MAX15090BEWI+T"
ROOM"NIC_P12V_MAM_TIC_BOM1"
PART_TYPE"SMLF"
CDS_LIB"pure_quanta"
PIN_NAMES_ROTATE"True"
CDS_LMAN_SYM_OUTLINE"-250,550,250,-550"
PART_NUMBER"AL015080B00";
"PG"
$PN"D7"66;
"FAULT# \B"
$PN"C7"75;
"GND_C2"
$PN"C2"32;
"GND_C1"
$PN"C1"32;
"GND_B2"
$PN"B2"32;
"CDLY"
$PN"A7"32;
"GATE"
$PN"A6"22;
"OUT_D6"
$PN"D6"76;
"OUT_D4"
$PN"D4"76;
"OUT_C6"
$PN"C6"76;
"OUT_C4"
$PN"C4"76;
"OUT_B6"
$PN"B6"76;
"OUT_B4"
$PN"B4"76;
"OUT_A4"
$PN"A4"76;
"ISENSE"
$PN"A1"21;
"OV"
$PN"D3"26;
"UV"
$PN"D2"31;
"REG"
$PN"D1"58;
"EN# \B"
$PN"B7"36;
"CB"
$PN"B1"74;
"IN_D5"
$PN"D5"24;
"IN_C5"
$PN"C5"24;
"IN_C3"
$PN"C3"24;
"IN_B5"
$PN"B5"24;
"IN_B3"
$PN"B3"24;
"IN_A5"
$PN"A5"24;
"IN_A3"
$PN"A3"24;
"VCC"
$PN"A2"25;
%"UNIVERSAL_POWER"
"1","(8350,9600)","0","pure_quanta_power","I52";
;
HDL_POWER"P3V3_AUX"
CDS_LIB"pure_quanta_power";
"A"35;
%"GND"
"1","(6250,10650)","0","pure_quanta_power","I53";
;
CDS_LIB"pure_quanta_power"
SIZE"1B"
HDL_POWER"GND";
"A<SIZE-1..0>\NAC"34;
%"Q_CAP"
"1","(6575,10725)","1","pure_quanta","I54";
;
LOCATION"PC2087"
$SEC"1"
CDS_SEC"1"
VOLTAGE"25V"
PACK_TYPE"C0402"
ROOM"NIC_P12V_MAM_TIC_BOM1"
VALUE"1UF"
TOLERANCE"10%"
CDS_LIB"pure_quanta"
MATERIAL"X6S"
PART_NUMBER"CH5104KEB02";
"B"
$PN"2"58;
"A"
$PN"1"34;
%"Q_CAP"
"1","(6350,11025)","0","pure_quanta","I55";
;
LOCATION"PC2085"
$SEC"1"
CDS_SEC"1"
MATERIAL"X6S"
VALUE"1UF"
VOLTAGE"25V"
PACK_TYPE"C0402"
ROOM"NIC_P12V_MAM_TIC_BOM1"
CDS_LIB"pure_quanta"
TOLERANCE"10%"
PART_NUMBER"CH5104KEB02";
"B"
$PN"2"34;
"A"
$PN"1"25;
%"Q_RES"
"2","(6350,11450)","0","pure_quanta","I56";
;
LOCATION"PR3792"
$SEC"1"
CDS_SEC"1"
WATTAGE"1/16W"
TOLERANCE"1%"
VALUE"10"
MATERIAL"CHIP"
PACK_TYPE"0402LF"
ROOM"NIC_P12V_MAM_TIC_BOM1"
CDS_LIB"pure_quanta"
PART_NUMBER"CS01002FB07";
"A"
$PN"1"24;
"B"
$PN"2"25;
%"GND"
"1","(6250,12000)","0","pure_quanta_power","I57";
;
SIZE"1B"
CDS_LIB"pure_quanta_power"
HDL_POWER"GND";
"A<SIZE-1..0>\NAC"12;
%"GND"
"1","(7100,11975)","0","pure_quanta_power","I58";
;
CDS_LIB"pure_quanta_power"
SIZE"1B"
HDL_POWER"GND";
"A<SIZE-1..0>\NAC"69;
%"Q_RES"
"2","(4225,12475)","0","pure_quanta","I59";
;
LOCATION"R4070"
$SEC"1"
CDS_SEC"1"
ROOM"NIC_P3V3_BOM1"
WATTAGE"1/16W"
VALUE"10K"
PACK_TYPE"0402LF"
TOLERANCE"1%"
MATERIAL"CHIP"
CDS_LIB"pure_quanta"
PART_NUMBER"CS31002FB08";
"A"
$PN"1"13;
"B"
$PN"2"60;
%"UNIVERSAL_POWER"
"1","(4225,12725)","0","pure_quanta_power","I60";
;
HDL_POWER"P12V_AUX"
CDS_LIB"pure_quanta_power";
"A"13;
%"Q_RES"
"1","(5650,12875)","0","pure_quanta","I61";
;
LOCATION"R3785"
$SEC"1"
CDS_SEC"1"
VALUE"0"
WATTAGE"1/16W"
TOLERANCE"5%"
MATERIAL"CHIP"
ROOM"NIC_P3V3_BOM1"
PACK_TYPE"0402LF"
CDS_LIB"pure_quanta"
PART_NUMBER"CS00002JB13";
"B"
$PN"2"57;
"A"
$PN"1"70;
%"Q_CAP"
"1","(5900,13500)","0","pure_quanta","I62";
;
LOCATION"PC5328"
$SEC"1"
CDS_SEC"1"
PACK_TYPE"C0402"
MATERIAL"X6S"
VOLTAGE"25V"
VALUE"1UF"
CDS_LIB"pure_quanta"
TOLERANCE"10%"
PART_NUMBER"CH5104KEB02";
"B"
$PN"2"2;
"A"
$PN"1"33;
%"UNIVERSAL_POWER"
"1","(5900,13850)","0","pure_quanta_power","I63";
;
HDL_POWER"P3V3_AUX"
CDS_LIB"pure_quanta_power";
"A"33;
%"Q_RES"
"2","(6250,12525)","0","pure_quanta","I64";
;
LOCATION"PR3790"
$SEC"1"
CDS_SEC"1"
WATTAGE"1/16W"
TOLERANCE"1%"
VALUE"7.15K"
MATERIAL"CHIP"
ROOM"NIC_P3V3_BOM1"
PACK_TYPE"0402LF"
CDS_LIB"pure_quanta"
PART_NUMBER"CS27152FB03";
"A"
$PN"1"57;
"B"
$PN"2"50;
%"GND"
"1","(6575,12700)","0","pure_quanta_power","I65";
;
CDS_LIB"pure_quanta_power"
SIZE"1B"
HDL_POWER"GND";
"A<SIZE-1..0>\NAC"14;
%"Q_RES"
"2","(6250,13250)","0","pure_quanta","I66";
;
LOCATION"PR3789"
$SEC"1"
CDS_SEC"1"
ROOM"NIC_P3V3_BOM1"
PACK_TYPE"0402LF"
VALUE"25.5K"
MATERIAL"CHIP"
WATTAGE"1/16W"
TOLERANCE"1%"
CDS_LIB"pure_quanta"
PART_NUMBER"CS32552FB06";
"A"
$PN"1"33;
"B"
$PN"2"57;
%"Q_CAP"
"1","(6800,12775)","1","pure_quanta","I67";
;
LOCATION"PC2093"
$SEC"1"
CDS_SEC"1"
PACK_TYPE"C0402"
ROOM"NIC_P3V3_BOM1"
VALUE"1UF"
VOLTAGE"25V"
MATERIAL"X6S"
CDS_LIB"pure_quanta"
TOLERANCE"10%"
PART_NUMBER"CH5104KEB02";
"B"
$PN"2"44;
"A"
$PN"1"14;
%"Q_RES"
"2","(6575,13500)","0","pure_quanta","I68";
;
LOCATION"PR3798"
$SEC"1"
CDS_SEC"1"
WATTAGE"1/16W"
PACK_TYPE"0402LF"
MATERIAL"CHIP"
TOLERANCE"1%"
VALUE"10"
ROOM"NIC_P3V3_BOM1"
CDS_LIB"pure_quanta"
PART_NUMBER"CS01002FB07";
"A"
$PN"1"33;
"B"
$PN"2"45;
%"Q_RES"
"2","(8350,9325)","0","pure_quanta","I71";
;
LOCATION"R1150"
$SEC"1"
CDS_SEC"1"
WATTAGE"1/16W"
TOLERANCE"1%"
MATERIAL"CHIP"
VALUE"10K"
PACK_TYPE"0402LF"
CDS_LIB"pure_quanta"
PART_NUMBER"CS31002FB08";
"A"
$PN"1"35;
"B"
$PN"2"52;
%"GND"
"1","(8350,10050)","0","pure_quanta_power","I72";
;
SIZE"1B"
CDS_LIB"pure_quanta_power"
HDL_POWER"GND";
"A<SIZE-1..0>\NAC"32;
%"Q_RES"
"2","(8475,10325)","0","pure_quanta","I73";
;
LOCATION"PR3781"
$SEC"1"
CDS_SEC"1"
MATERIAL"CHIP"
ROOM"NIC_P12V_MAM_TIC_BOM1"
VALUE"845"
WATTAGE"1/16W"
TOLERANCE"1%"
PACK_TYPE"0402LF"
CDS_LIB"pure_quanta"
PART_NUMBER"CS18452FB01";
"A"
$PN"1"21;
"B"
$PN"2"32;
%"Q_CAP"
"1","(8400,11050)","0","pure_quanta","I74";
;
LOCATION"PC2088"
$SEC"1"
CDS_SEC"1"
VOLTAGE"50V"
VALUE"0.01UF"
MATERIAL"EMPTY"
ROOM"NIC_P12V_MAM_TIC_BOM1"
PACK_TYPE"C0402"
CDS_LIB"pure_quanta"
TOLERANCE"10%"
PART_NUMBER"CH31006KB18";
"B"
$PN"2"22;
"A"
$PN"1"76;
%"Q_RES"
"1","(9125,10725)","0","pure_quanta","I75";
;
LOCATION"R3144"
$SEC"1"
CDS_SEC"1"
VALUE"0"
TOLERANCE"5%"
MATERIAL"CHIP"
ROOM"NIC_P12V_MAM_TIC_BOM1"
PACK_TYPE"0402LF"
WATTAGE"1/16W"
CDS_LIB"pure_quanta"
PART_NUMBER"CS00002JB13";
"B"
$PN"2"72;
"A"
$PN"1"66;
%"Q_RES"
"2","(8725,11050)","0","pure_quanta","I76";
;
LOCATION"PR4524"
$SEC"1"
CDS_SEC"1"
TOLERANCE"1%"
MATERIAL"CHIP"
WATTAGE"1/16W"
VALUE"10M"
ROOM"NIC_P12V_MAM_TIC_BOM1"
PACK_TYPE"0402LF"
CDS_LIB"pure_quanta"
PART_NUMBER"CS61002FB02";
"A"
$PN"1"76;
"B"
$PN"2"22;
%"Q_CAP"
"1","(9075,10825)","1","pure_quanta","I77";
;
LOCATION"PC4056"
$SEC"1"
CDS_SEC"1"
VOLTAGE"50V"
PACK_TYPE"C0402"
VALUE"3900PF"
ROOM"NIC_P12V_MAM_TIC_BOM1"
CDS_LIB"pure_quanta"
MATERIAL"X7R"
TOLERANCE"10%"
PART_NUMBER"CH23906KB14";
"B"
$PN"2"15;
"A"
$PN"1"22;
%"GND"
"1","(8575,12100)","0","pure_quanta_power","I78";
;
CDS_LIB"pure_quanta_power"
SIZE"1B"
HDL_POWER"GND";
"A<SIZE-1..0>\NAC"28;
%"SCHOTTKY_AC"
"1","(8825,11700)","1","pure_quanta","I79";
;
LOCATION"PD102"
$SEC"1"
CDS_SEC"1"
VALUE"B340A-13-F"
MATERIAL"IC"
CDS_LMAN_SYM_OUTLINE"-75,50,75,-50"
CDS_LIB"pure_quanta"
NEEDS_NO_SIZE"TRUE"
PART_TYPE"SMLF"
PART_NUMBER"BC000340Z30";
"C"
$PN"C"76;
"A"
$PN"A"23;
%"Q_RES"
"1","(9375,10400)","0","pure_quanta","I80";
;
LOCATION"R3870"
$SEC"1"
CDS_SEC"1"
WATTAGE"1/16W"
MATERIAL"CHIP"
VALUE"0"
PACK_TYPE"0402LF"
TOLERANCE"5%"
ROOM"NIC_P12V_MAM_TIC_BOM1"
CDS_LIB"pure_quanta"
PART_NUMBER"CS00002JB13";
"B"
$PN"2"68;
"A"
$PN"1"21;
%"GND"
"1","(9200,10750)","0","pure_quanta_power","I81";
;
SIZE"1B"
CDS_LIB"pure_quanta_power"
HDL_POWER"GND";
"A<SIZE-1..0>\NAC"15;
%"Q_RES"
"1","(9375,10525)","0","pure_quanta","I82";
;
LOCATION"R3869"
$SEC"1"
CDS_SEC"1"
MATERIAL"EMPTY"
VALUE"0"
WATTAGE"1/16W"
PACK_TYPE"0402LF"
TOLERANCE"5%"
CDS_LIB"pure_quanta"
PART_NUMBER"CS00002JB13";
"B"
$PN"2"67;
"A"
$PN"1"21;
%"Q_RES"
"2","(9475,11000)","0","pure_quanta","I83";
;
LOCATION"R3799"
$SEC"1"
CDS_SEC"1"
VALUE"100K"
ROOM"NIC_P12V_MAM_TIC_BOM1"
MATERIAL"CHIP"
PACK_TYPE"0402LF"
WATTAGE"1/16W"
TOLERANCE"1%"
CDS_LIB"pure_quanta"
PART_NUMBER"CS41002FB09";
"A"
$PN"1"30;
"B"
$PN"2"75;
%"VCCAUX15"
"1","(9650,11300)","0","pure_quanta_power","I84";
;
HDL_POWER"P3V3_AUX"
CDS_LIB"pure_quanta_power";
"A"30;
%"Q_RES"
"2","(9900,11000)","0","pure_quanta","I85";
;
LOCATION"R3797"
$SEC"1"
CDS_SEC"1"
TOLERANCE"1%"
WATTAGE"1/16W"
MATERIAL"CHIP"
PACK_TYPE"0402LF"
ROOM"NIC_P12V_MAM_TIC_BOM1"
VALUE"100K"
CDS_LIB"pure_quanta"
PART_NUMBER"CS41002FB09";
"A"
$PN"1"30;
"B"
$PN"2"72;
%"Q_CAP"
"1","(9300,11675)","0","pure_quanta","I86";
;
LOCATION"PC2092"
$SEC"1"
CDS_SEC"1"
PACK_TYPE"0402"
MATERIAL"X7R"
VOLTAGE"25V"
VALUE"0.1UF"
CDS_LIB"pure_quanta"
TOLERANCE"10%"
PART_NUMBER"CH4104K1B00";
"B"
$PN"2"23;
"A"
$PN"1"76;
%"Q_CAP"
"1","(9725,11675)","0","pure_quanta","I87";
;
LOCATION"PC2080"
$SEC"1"
CDS_SEC"1"
PACK_TYPE"C0805"
VALUE"22UF"
MATERIAL"X6S"
VOLTAGE"16V"
CDS_LIB"pure_quanta"
TOLERANCE"20%"
PART_NUMBER"CH6223MEA01";
"B"
$PN"2"23;
"A"
$PN"1"76;
%"GND"
"1","(10125,11325)","0","pure_quanta_power","I88";
;
CDS_LIB"pure_quanta_power"
SIZE"1B"
HDL_POWER"GND";
"A<SIZE-1..0>\NAC"23;
%"Q_CAP"
"1","(10125,11675)","0","pure_quanta","I89";
;
LOCATION"PC2082"
$SEC"1"
CDS_SEC"1"
VALUE"10UF"
VOLTAGE"16V"
MATERIAL"X6S"
PACK_TYPE"C0805"
CDS_LIB"pure_quanta"
TOLERANCE"10%"
PART_NUMBER"CH6103KEA01";
"B"
$PN"2"23;
"A"
$PN"1"76;
%"Q_RES"
"2","(3900,8850)","0","pure_quanta","I9";
;
LOCATION"R1906"
$SEC"1"
CDS_SEC"1"
VALUE"1K"
TOLERANCE"1%"
PACK_TYPE"0402LF"
WATTAGE"1/16W"
MATERIAL"CHIP"
CDS_LIB"pure_quanta"
PART_NUMBER"CS21002FB06";
"A"
$PN"1"19;
"B"
$PN"2"55;
%"UNIVERSAL_POWER"
"1","(10125,11975)","2","pure_quanta_power","I90";
;
HDL_POWER"P12V_OCP_SFF"
CDS_LIB"pure_quanta_power";
"A"76;
%"Q_CAP"
"1","(8675,13100)","0","pure_quanta","I94";
;
LOCATION"PC2144"
$SEC"1"
CDS_SEC"1"
VOLTAGE"50V"
MATERIAL"EMPTY"
PACK_TYPE"C0402"
ROOM"NIC_P3V3_BOM1"
VALUE"0.01UF"
CDS_LIB"pure_quanta"
TOLERANCE"10%"
PART_NUMBER"CH31006KB18";
"B"
$PN"2"49;
"A"
$PN"1"41;
%"Q_RES"
"2","(8700,12425)","0","pure_quanta","I95";
;
LOCATION"PR5481"
$SEC"1"
CDS_SEC"1"
MATERIAL"CHIP"
PACK_TYPE"0402LF"
WATTAGE"1/16W"
ROOM"NIC_P3V3_BOM1"
VALUE"4.53K"
TOLERANCE"1%"
CDS_LIB"pure_quanta"
PART_NUMBER"CS24532FB03";
"A"
$PN"1"29;
"B"
$PN"2"28;
%"Q_RES"
"2","(8925,13100)","0","pure_quanta","I96";
;
LOCATION"PR4525"
$SEC"1"
CDS_SEC"1"
MATERIAL"CHIP"
ROOM"NIC_P3V3_BOM1"
PACK_TYPE"0402LF"
TOLERANCE"1%"
VALUE"10M"
WATTAGE"1/16W"
CDS_LIB"pure_quanta"
PART_NUMBER"CS61002FB02";
"A"
$PN"1"41;
"B"
$PN"2"49;
%"SCHOTTKY_AC"
"1","(9050,13675)","1","pure_quanta","I97";
;
LOCATION"PD103"
$SEC"1"
CDS_SEC"1"
MATERIAL"IC"
VALUE"B340A-13-F"
NEEDS_NO_SIZE"TRUE"
PART_TYPE"SMLF"
CDS_LIB"pure_quanta"
CDS_LMAN_SYM_OUTLINE"-75,50,75,-50"
PART_NUMBER"BC000340Z30";
"C"
$PN"C"41;
"A"
$PN"A"42;
%"GND"
"1","(9575,12800)","0","pure_quanta_power","I99";
;
CDS_LIB"pure_quanta_power"
SIZE"1B"
HDL_POWER"GND";
"A<SIZE-1..0>\NAC"16;
END.
